# BASEBOARD_FAB2 (Tioga Pass) — schematic netlist excerpt (pin names and nets, part order shuffled) for the footprints in the layout excerpt that follows; sources: Cadence DE-HDL packaged netlist, KiCad conversion of Wiwynn_Tioga_Pass_MB.brd

C9N9  CAP  0.22UF 16V 10% X7R  pkg 0402  page 182 : A = P3E_CPU1_PE3_MP_C_TXN<15> ; B = P3E_CPU1_PE3_MP_TXN<15>
R6W28  RES  4.75K 1% CHIP  pkg 0402  page 247 : A = P3V3_STBY ; B = HSC_SMBUS_SWITCH_EN
C3U2  CAP  10UF 16V 10% X6S  pkg 0805  page 216 : A = VR_FET_SW_P12V_STBY_PVDDQ_ABC ; B = GND

(kicad_pcb
	(version 20260206)
	(generator "pcbnew")
	(generator_version "10.0")
	(general
		(thickness 1.6)
		(legacy_teardrops no)
	)
	(paper "A4")
	(title_block
		(title "Wiwynn_Tioga_Pass_MB.brd")
		(comment 1 "Tioga Pass / footprints 3186-3188 of 4770")
	)
	(layers
		(0 "F.Cu" signal "TOP")
		(4 "In1.Cu" signal "L2GND")
		(6 "In2.Cu" signal "L3")
		(8 "In3.Cu" signal "L4GND")
		(10 "In4.Cu" signal "L5")
		(12 "In5.Cu" signal "L6GND")
		(14 "In6.Cu" signal "L7VCC")
		(16 "In7.Cu" signal "L8VCC")
		(18 "In8.Cu" signal "L9GND")
		(20 "In9.Cu" signal "L10")
		(22 "In10.Cu" signal "L11GND")
		(24 "In11.Cu" signal "L12")
		(26 "In12.Cu" signal "L13GND")
		(2 "B.Cu" signal "BOTTOM")
		(9 "F.Adhes" user "F.Adhesive")
		(11 "B.Adhes" user "B.Adhesive")
		(13 "F.Paste" user "Package Geometry/Pastemask Top")
		(15 "B.Paste" user "Package Geometry/Pastemask Bottom")
		(5 "F.SilkS" user "Ref Des/Silkscreen Top")
		(7 "B.SilkS" user "Ref Des/Silkscreen Bottom")
		(1 "F.Mask" user "Board Geometry/Soldermask Top")
		(3 "B.Mask" user "Board Geometry/Soldermask Bottom")
		(17 "Dwgs.User" user "User.Drawings")
		(19 "Cmts.User" user "User.Comments")
		(21 "Eco1.User" user "User.Eco1")
		(23 "Eco2.User" user "User.Eco2")
		(25 "Edge.Cuts" user "Board Geometry/Outline")
		(27 "Margin" user)
		(31 "F.CrtYd" user "Package Geometry/Place Bound Top")
		(29 "B.CrtYd" user "Package Geometry/Place Bound Bottom")
		(35 "F.Fab" user "Ref Des/Assembly Top")
		(33 "B.Fab" user "Ref Des/Assembly Bottom")
	)
	(footprint ""
		(layer "B.Cu")
		(at 17.83842 -102.45852 90)
		(property "Reference" "C9N9"
			(at 0 0 90)
			(layer "B.SilkS")
			(hide yes)
			(effects
				(font
					(size 1.27 1.27)
				)
				(justify mirror)
			)
		)
		(property "Value" ""
			(at 0 0 90)
			(layer "B.Fab")
			(effects
				(font
					(size 1.27 1.27)
				)
				(justify mirror)
			)
		)
		(duplicate_pad_numbers_are_jumpers no)
		(fp_poly
			(pts
				(xy -0.3048 -0.1016) (xy -0.3048 0.9906) (xy 0.3048 0.9906) (xy 0.3048 -0.1016)
			)
			(stroke
				(width 0)
				(type default)
			)
			(fill no)
			(layer "B.CrtYd")
		)
		(fp_line
			(start 0.3048 -0.1016)
			(end 0.3048 0.9906)
			(stroke
				(width 0.1)
				(type default)
			)
			(layer "B.Fab")
		)
		(fp_line
			(start -0.3048 -0.1016)
			(end 0.3048 -0.1016)
			(stroke
				(width 0.1)
				(type default)
			)
			(layer "B.Fab")
		)
		(fp_line
			(start 0.3048 0.9906)
			(end -0.3048 0.9906)
			(stroke
				(width 0.1)
				(type default)
			)
			(layer "B.Fab")
		)
		(fp_line
			(start -0.3048 0.9906)
			(end -0.3048 -0.1016)
			(stroke
				(width 0.1)
				(type default)
			)
			(layer "B.Fab")
		)
		(pad "1" smd rect
			(at 0 0 270)
			(size 0.508 0.508)
			(layers "B.Cu" "B.Mask" "B.Paste")
			(net "P3E_CPU1_PE3_MP_C_TXN<15>")
		)
		(pad "2" smd rect
			(at 0 0.889 270)
			(size 0.508 0.508)
			(layers "B.Cu" "B.Mask" "B.Paste")
			(net "P3E_CPU1_PE3_MP_TXN<15>")
		)
		(zone
			(layer "B.Cu")
			(hatch none 0.5)
			(connect_pads
				(clearance 0)
			)
			(min_thickness 0.25)
			(keepout
				(tracks allowed)
				(vias not_allowed)
				(pads allowed)
				(copperpour not_allowed)
				(footprints allowed)
			)
			(placement
				(enabled no)
				(sheetname "")
			)
			(fill
				(thermal_gap 0.5)
				(thermal_bridge_width 0.5)
				(island_removal_mode 0)
			)
			(polygon
				(pts
					(xy 18.09242 -102.71252) (xy 18.09242 -102.20452) (xy 18.47342 -102.20452) (xy 18.47342 -102.71252)
				)
			)
		)
		(zone
			(layer "B.Cu")
			(hatch none 0.5)
			(connect_pads
				(clearance 0)
			)
			(min_thickness 0.25)
			(keepout
				(tracks not_allowed)
				(vias allowed)
				(pads allowed)
				(copperpour not_allowed)
				(footprints allowed)
			)
			(placement
				(enabled no)
				(sheetname "")
			)
			(fill
				(thermal_gap 0.5)
				(thermal_bridge_width 0.5)
				(island_removal_mode 0)
			)
			(polygon
				(pts
					(xy 18.47342 -102.71252) (xy 18.47342 -102.20452) (xy 18.09242 -102.20452) (xy 18.09242 -102.71252)
				)
			)
		)
	)
	(footprint ""
		(layer "B.Cu")
		(at 403.344634 -79.235808 90)
		(property "Reference" "R6W28"
			(at 0.8382 -0.67818 90)
			(unlocked yes)
			(layer "B.SilkS")
			(effects
				(font
					(size 0.4064 0.254)
					(thickness 0.1524)
				)
				(justify left mirror)
			)
		)
		(property "Value" ""
			(at 0 0 90)
			(layer "B.Fab")
			(effects
				(font
					(size 1.27 1.27)
				)
				(justify mirror)
			)
		)
		(duplicate_pad_numbers_are_jumpers no)
		(fp_poly
			(pts
				(xy 0.2794 -0.1016) (xy -0.2794 -0.1016) (xy -0.2794 0.9906) (xy 0.2794 0.9906)
			)
			(stroke
				(width 0)
				(type default)
			)
			(fill no)
			(layer "B.CrtYd")
		)
		(fp_line
			(start 0.2794 -0.1016)
			(end 0.2794 0.9906)
			(stroke
				(width 0.1)
				(type default)
			)
			(layer "B.Fab")
		)
		(fp_line
			(start -0.2794 -0.1016)
			(end 0.2794 -0.1016)
			(stroke
				(width 0.1)
				(type default)
			)
			(layer "B.Fab")
		)
		(fp_line
			(start 0.2794 0.9906)
			(end -0.2794 0.9906)
			(stroke
				(width 0.1)
				(type default)
			)
			(layer "B.Fab")
		)
		(fp_line
			(start -0.2794 0.9906)
			(end -0.2794 -0.1016)
			(stroke
				(width 0.1)
				(type default)
			)
			(layer "B.Fab")
		)
		(pad "1" smd rect
			(at 0 0 270)
			(size 0.508 0.508)
			(layers "B.Cu" "B.Mask" "B.Paste")
			(net "P3V3_STBY")
		)
		(pad "2" smd rect
			(at 0 0.889 270)
			(size 0.508 0.508)
			(layers "B.Cu" "B.Mask" "B.Paste")
			(net "HSC_SMBUS_SWITCH_EN")
		)
		(zone
			(layer "B.Cu")
			(hatch none 0.5)
			(connect_pads
				(clearance 0)
			)
			(min_thickness 0.25)
			(keepout
				(tracks allowed)
				(vias not_allowed)
				(pads allowed)
				(copperpour not_allowed)
				(footprints allowed)
			)
			(placement
				(enabled no)
				(sheetname "")
			)
			(fill
				(thermal_gap 0.5)
				(thermal_bridge_width 0.5)
				(island_removal_mode 0)
			)
			(polygon
				(pts
					(xy 403.598634 -79.489808) (xy 403.598634 -78.981808) (xy 403.979634 -78.981808) (xy 403.979634 -79.489808)
				)
			)
		)
		(zone
			(layer "B.Cu")
			(hatch none 0.5)
			(connect_pads
				(clearance 0)
			)
			(min_thickness 0.25)
			(keepout
				(tracks not_allowed)
				(vias allowed)
				(pads allowed)
				(copperpour not_allowed)
				(footprints allowed)
			)
			(placement
				(enabled no)
				(sheetname "")
			)
			(fill
				(thermal_gap 0.5)
				(thermal_bridge_width 0.5)
				(island_removal_mode 0)
			)
			(polygon
				(pts
					(xy 403.979634 -79.489808) (xy 403.979634 -78.981808) (xy 403.598634 -78.981808) (xy 403.598634 -79.489808)
				)
			)
		)
	)
	(footprint ""
		(layer "B.Cu")
		(at 347.5736 -7.1628 -90)
		(property "Reference" "C3U2"
			(at 0 0 90)
			(layer "B.SilkS")
			(hide yes)
			(effects
				(font
					(size 1.27 1.27)
				)
				(justify mirror)
			)
		)
		(property "Value" ""
			(at 0 0 90)
			(layer "B.Fab")
			(effects
				(font
					(size 1.27 1.27)
				)
				(justify mirror)
			)
		)
		(duplicate_pad_numbers_are_jumpers no)
		(fp_rect
			(start 0.7239 1.9939)
			(end -0.7239 -0.2159)
			(stroke
				(width 0)
				(type default)
			)
			(fill no)
			(layer "B.CrtYd")
		)
		(fp_line
			(start -0.7239 1.9939)
			(end -0.7239 -0.2159)
			(stroke
				(width 0.1)
				(type default)
			)
			(layer "B.Fab")
		)
		(fp_line
			(start 0.7239 1.9939)
			(end -0.7239 1.9939)
			(stroke
				(width 0.1)
				(type default)
			)
			(layer "B.Fab")
		)
		(fp_line
			(start -0.7239 -0.2159)
			(end 0.7239 -0.2159)
			(stroke
				(width 0.1)
				(type default)
			)
			(layer "B.Fab")
		)
		(fp_line
			(start 0.7239 -0.2159)
			(end 0.7239 1.9939)
			(stroke
				(width 0.1)
				(type default)
			)
			(layer "B.Fab")
		)
		(pad "1" smd rect
			(at 0 0 90)
			(size 1.27 1.016)
			(layers "B.Cu" "B.Mask" "B.Paste")
			(net "VR_FET_SW_P12V_STBY_PVDDQ_ABC")
		)
		(pad "2" smd rect
			(at 0 1.778 90)
			(size 1.27 1.016)
			(layers "B.Cu" "B.Mask" "B.Paste")
			(net "GND")
		)
		(zone
			(layer "B.Cu")
			(hatch none 0.5)
			(connect_pads
				(clearance 0)
			)
			(min_thickness 0.25)
			(keepout
				(tracks not_allowed)
				(vias allowed)
				(pads allowed)
				(copperpour not_allowed)
				(footprints allowed)
			)
			(placement
				(enabled no)
				(sheetname "")
			)
			(fill
				(thermal_gap 0.5)
				(thermal_bridge_width 0.5)
				(island_removal_mode 0)
			)
			(polygon
				(pts
					(xy 346.3036 -6.5278) (xy 347.0656 -6.5278) (xy 347.0656 -7.7978) (xy 346.3036 -7.7978)
				)
			)
		)
	)
)
